(kicad_pcb
	(version 20260206)
	(generator "pcbnew")
	(generator_version "10.0")
	(general
		(thickness 1.6)
		(legacy_teardrops no)
	)
	(paper "A4")
	(title_block
		(title "Wiwynn_Tioga_Pass_MB.brd")
		(comment 1 "Tioga Pass / footprints 4081-4083 of 4770")
	)
	(layers
		(0 "F.Cu" signal "TOP")
		(4 "In1.Cu" signal "L2GND")
		(6 "In2.Cu" signal "L3")
		(8 "In3.Cu" signal "L4GND")
		(10 "In4.Cu" signal "L5")
		(12 "In5.Cu" signal "L6GND")
		(14 "In6.Cu" signal "L7VCC")
		(16 "In7.Cu" signal "L8VCC")
		(18 "In8.Cu" signal "L9GND")
		(20 "In9.Cu" signal "L10")
		(22 "In10.Cu" signal "L11GND")
		(24 "In11.Cu" signal "L12")
		(26 "In12.Cu" signal "L13GND")
		(2 "B.Cu" signal "BOTTOM")
		(9 "F.Adhes" user "F.Adhesive")
		(11 "B.Adhes" user "B.Adhesive")
		(13 "F.Paste" user "Package Geometry/Pastemask Top")
		(15 "B.Paste" user "Package Geometry/Pastemask Bottom")
		(5 "F.SilkS" user "Ref Des/Silkscreen Top")
		(7 "B.SilkS" user "Ref Des/Silkscreen Bottom")
		(1 "F.Mask" user "Board Geometry/Soldermask Top")
		(3 "B.Mask" user "Board Geometry/Soldermask Bottom")
		(17 "Dwgs.User" user "User.Drawings")
		(19 "Cmts.User" user "User.Comments")
		(21 "Eco1.User" user "User.Eco1")
		(23 "Eco2.User" user "User.Eco2")
		(25 "Edge.Cuts" user "Board Geometry/Outline")
		(27 "Margin" user)
		(31 "F.CrtYd" user "Package Geometry/Place Bound Top")
		(29 "B.CrtYd" user "Package Geometry/Place Bound Bottom")
		(35 "F.Fab" user "Ref Des/Assembly Top")
		(33 "B.Fab" user "Ref Des/Assembly Bottom")
	)
	(footprint ""
		(layer "B.Cu")
		(at 424.18 -141.986)
		(property "Reference" "C2L42"
			(at 0 0 0)
			(layer "B.SilkS")
			(hide yes)
			(effects
				(font
					(size 1.27 1.27)
				)
				(justify mirror)
			)
		)
		(property "Value" ""
			(at 0 0 0)
			(layer "B.Fab")
			(effects
				(font
					(size 1.27 1.27)
				)
				(justify mirror)
			)
		)
		(duplicate_pad_numbers_are_jumpers no)
		(fp_poly
			(pts
				(xy -0.3048 -0.1016) (xy -0.3048 0.9906) (xy 0.3048 0.9906) (xy 0.3048 -0.1016)
			)
			(stroke
				(width 0)
				(type default)
			)
			(fill no)
			(layer "B.CrtYd")
		)
		(fp_line
			(start -0.3048 -0.1016)
			(end 0.3048 -0.1016)
			(stroke
				(width 0.1)
				(type default)
			)
			(layer "B.Fab")
		)
		(fp_line
			(start -0.3048 0.9906)
			(end -0.3048 -0.1016)
			(stroke
				(width 0.1)
				(type default)
			)
			(layer "B.Fab")
		)
		(fp_line
			(start 0.3048 -0.1016)
			(end 0.3048 0.9906)
			(stroke
				(width 0.1)
				(type default)
			)
			(layer "B.Fab")
		)
		(fp_line
			(start 0.3048 0.9906)
			(end -0.3048 0.9906)
			(stroke
				(width 0.1)
				(type default)
			)
			(layer "B.Fab")
		)
		(pad "1" smd rect
			(at 0 0 180)
			(size 0.508 0.508)
			(layers "B.Cu" "B.Mask" "B.Paste")
			(net "SATA6G_P2_TX_C_DN")
		)
		(pad "2" smd rect
			(at 0 0.889 180)
			(size 0.508 0.508)
			(layers "B.Cu" "B.Mask" "B.Paste")
			(net "SATA6G_PCH_PCIE_UP_SATA_TXN<2>")
		)
		(zone
			(layer "B.Cu")
			(hatch none 0.5)
			(connect_pads
				(clearance 0)
			)
			(min_thickness 0.25)
			(keepout
				(tracks allowed)
				(vias not_allowed)
				(pads allowed)
				(copperpour not_allowed)
				(footprints allowed)
			)
			(placement
				(enabled no)
				(sheetname "")
			)
			(fill
				(thermal_gap 0.5)
				(thermal_bridge_width 0.5)
				(island_removal_mode 0)
			)
			(polygon
				(pts
					(xy 424.434 -141.732) (xy 423.926 -141.732) (xy 423.926 -141.351) (xy 424.434 -141.351)
				)
			)
		)
		(zone
			(layer "B.Cu")
			(hatch none 0.5)
			(connect_pads
				(clearance 0)
			)
			(min_thickness 0.25)
			(keepout
				(tracks not_allowed)
				(vias allowed)
				(pads allowed)
				(copperpour not_allowed)
				(footprints allowed)
			)
			(placement
				(enabled no)
				(sheetname "")
			)
			(fill
				(thermal_gap 0.5)
				(thermal_bridge_width 0.5)
				(island_removal_mode 0)
			)
			(polygon
				(pts
					(xy 424.434 -141.351) (xy 423.926 -141.351) (xy 423.926 -141.732) (xy 424.434 -141.732)
				)
			)
		)
	)
	(footprint ""
		(layer "B.Cu")
		(at 417.81222 -39.0398 180)
		(property "Reference" "C25W41"
			(at 0.8382 -0.67818 180)
			(unlocked yes)
			(layer "B.SilkS")
			(effects
				(font
					(size 0.4064 0.254)
					(thickness 0.1524)
				)
				(justify left mirror)
			)
		)
		(property "Value" ""
			(at 0 0 0)
			(layer "B.Fab")
			(effects
				(font
					(size 1.27 1.27)
				)
				(justify mirror)
			)
		)
		(duplicate_pad_numbers_are_jumpers no)
		(fp_poly
			(pts
				(xy -0.3048 -0.1016) (xy -0.3048 0.9906) (xy 0.3048 0.9906) (xy 0.3048 -0.1016)
			)
			(stroke
				(width 0)
				(type default)
			)
			(fill no)
			(layer "B.CrtYd")
		)
		(fp_line
			(start 0.3048 0.9906)
			(end -0.3048 0.9906)
			(stroke
				(width 0.1)
				(type default)
			)
			(layer "B.Fab")
		)
		(fp_line
			(start 0.3048 -0.1016)
			(end 0.3048 0.9906)
			(stroke
				(width 0.1)
				(type default)
			)
			(layer "B.Fab")
		)
		(fp_line
			(start -0.3048 0.9906)
			(end -0.3048 -0.1016)
			(stroke
				(width 0.1)
				(type default)
			)
			(layer "B.Fab")
		)
		(fp_line
			(start -0.3048 -0.1016)
			(end 0.3048 -0.1016)
			(stroke
				(width 0.1)
				(type default)
			)
			(layer "B.Fab")
		)
		(pad "1" smd rect
			(at 0 0)
			(size 0.508 0.508)
			(layers "B.Cu" "B.Mask" "B.Paste")
			(net "VCC_D_3V3")
		)
		(pad "2" smd rect
			(at 0 0.889)
			(size 0.508 0.508)
			(layers "B.Cu" "B.Mask" "B.Paste")
			(net "GND")
		)
		(zone
			(layer "B.Cu")
			(hatch none 0.5)
			(connect_pads
				(clearance 0)
			)
			(min_thickness 0.25)
			(keepout
				(tracks not_allowed)
				(vias allowed)
				(pads allowed)
				(copperpour not_allowed)
				(footprints allowed)
			)
			(placement
				(enabled no)
				(sheetname "")
			)
			(fill
				(thermal_gap 0.5)
				(thermal_bridge_width 0.5)
				(island_removal_mode 0)
			)
			(polygon
				(pts
					(xy 417.55822 -39.6748) (xy 418.06622 -39.6748) (xy 418.06622 -39.2938) (xy 417.55822 -39.2938)
				)
			)
		)
		(zone
			(layer "B.Cu")
			(hatch none 0.5)
			(connect_pads
				(clearance 0)
			)
			(min_thickness 0.25)
			(keepout
				(tracks allowed)
				(vias not_allowed)
				(pads allowed)
				(copperpour not_allowed)
				(footprints allowed)
			)
			(placement
				(enabled no)
				(sheetname "")
			)
			(fill
				(thermal_gap 0.5)
				(thermal_bridge_width 0.5)
				(island_removal_mode 0)
			)
			(polygon
				(pts
					(xy 417.55822 -39.2938) (xy 418.06622 -39.2938) (xy 418.06622 -39.6748) (xy 417.55822 -39.6748)
				)
			)
		)
	)
	(footprint ""
		(layer "B.Cu")
		(at 30.452568 -8.122412 90)
		(property "Reference" "C9U7"
			(at 0 0 90)
			(layer "B.SilkS")
			(hide yes)
			(effects
				(font
					(size 1.27 1.27)
				)
				(justify mirror)
			)
		)
		(property "Value" ""
			(at 0 0 90)
			(layer "B.Fab")
			(effects
				(font
					(size 1.27 1.27)
				)
				(justify mirror)
			)
		)
		(duplicate_pad_numbers_are_jumpers no)
		(fp_poly
			(pts
				(xy -0.3048 -0.1016) (xy -0.3048 0.9906) (xy 0.3048 0.9906) (xy 0.3048 -0.1016)
			)
			(stroke
				(width 0)
				(type default)
			)
			(fill no)
			(layer "B.CrtYd")
		)
		(fp_line
			(start 0.3048 -0.1016)
			(end 0.3048 0.9906)
			(stroke
				(width 0.1)
				(type default)
			)
			(layer "B.Fab")
		)
		(fp_line
			(start -0.3048 -0.1016)
			(end 0.3048 -0.1016)
			(stroke
				(width 0.1)
				(type default)
			)
			(layer "B.Fab")
		)
		(fp_line
			(start 0.3048 0.9906)
			(end -0.3048 0.9906)
			(stroke
				(width 0.1)
				(type default)
			)
			(layer "B.Fab")
		)
		(fp_line
			(start -0.3048 0.9906)
			(end -0.3048 -0.1016)
			(stroke
				(width 0.1)
				(type default)
			)
			(layer "B.Fab")
		)
		(pad "1" smd rect
			(at 0 0 270)
			(size 0.508 0.508)
			(layers "B.Cu" "B.Mask" "B.Paste")
			(net "M_H_VREF")
		)
		(pad "2" smd rect
			(at 0 0.889 270)
			(size 0.508 0.508)
			(layers "B.Cu" "B.Mask" "B.Paste")
			(net "GND")
		)
		(zone
			(layer "B.Cu")
			(hatch none 0.5)
			(connect_pads
				(clearance 0)
			)
			(min_thickness 0.25)
			(keepout
				(tracks allowed)
				(vias not_allowed)
				(pads allowed)
				(copperpour not_allowed)
				(footprints allowed)
			)
			(placement
				(enabled no)
				(sheetname "")
			)
			(fill
				(thermal_gap 0.5)
				(thermal_bridge_width 0.5)
				(island_removal_mode 0)
			)
			(polygon
				(pts
					(xy 30.706568 -8.376412) (xy 30.706568 -7.868412) (xy 31.087568 -7.868412) (xy 31.087568 -8.376412)
				)
			)
		)
		(zone
			(layer "B.Cu")
			(hatch none 0.5)
			(connect_pads
				(clearance 0)
			)
			(min_thickness 0.25)
			(keepout
				(tracks not_allowed)
				(vias allowed)
				(pads allowed)
				(copperpour not_allowed)
				(footprints allowed)
			)
			(placement
				(enabled no)
				(sheetname "")
			)
			(fill
				(thermal_gap 0.5)
				(thermal_bridge_width 0.5)
				(island_removal_mode 0)
			)
			(polygon
				(pts
					(xy 31.087568 -8.376412) (xy 31.087568 -7.868412) (xy 30.706568 -7.868412) (xy 30.706568 -8.376412)
				)
			)
		)
	)
)
